# BASEBOARD_FAB2 (Tioga Pass) — schematic netlist excerpt (pin names and nets, part order shuffled) for the footprints in the layout excerpt that follows; sources: Cadence DE-HDL packaged netlist, KiCad conversion of Wiwynn_Tioga_Pass_MB.brd

T1P22  TPAD-DIFF-4P-GP  pkg DISCRET-GB3  page 256
  \1\  = L10_100OHM_6INCH_DP
  \2\  = L10_100OHM_6INCH_DN
  GND1  = GND
  GND2  = GND

C4D40  CAP_A  0.1UF 16V 10% X7R  pkg 0402V  page 213 : A = VR_PVCCIO_CPU1_VINSEN ; B = GND

(kicad_pcb
	(version 20260206)
	(generator "pcbnew")
	(generator_version "10.0")
	(general
		(thickness 1.6)
		(legacy_teardrops no)
	)
	(paper "A4")
	(title_block
		(title "Wiwynn_Tioga_Pass_MB.brd")
		(comment 1 "Tioga Pass / footprints 1650-1651 of 4770")
	)
	(layers
		(0 "F.Cu" signal "TOP")
		(4 "In1.Cu" signal "L2GND")
		(6 "In2.Cu" signal "L3")
		(8 "In3.Cu" signal "L4GND")
		(10 "In4.Cu" signal "L5")
		(12 "In5.Cu" signal "L6GND")
		(14 "In6.Cu" signal "L7VCC")
		(16 "In7.Cu" signal "L8VCC")
		(18 "In8.Cu" signal "L9GND")
		(20 "In9.Cu" signal "L10")
		(22 "In10.Cu" signal "L11GND")
		(24 "In11.Cu" signal "L12")
		(26 "In12.Cu" signal "L13GND")
		(2 "B.Cu" signal "BOTTOM")
		(9 "F.Adhes" user "F.Adhesive")
		(11 "B.Adhes" user "B.Adhesive")
		(13 "F.Paste" user "Package Geometry/Pastemask Top")
		(15 "B.Paste" user "Package Geometry/Pastemask Bottom")
		(5 "F.SilkS" user "Ref Des/Silkscreen Top")
		(7 "B.SilkS" user "Ref Des/Silkscreen Bottom")
		(1 "F.Mask" user "Board Geometry/Soldermask Top")
		(3 "B.Mask" user "Board Geometry/Soldermask Bottom")
		(17 "Dwgs.User" user "User.Drawings")
		(19 "Cmts.User" user "User.Comments")
		(21 "Eco1.User" user "User.Eco1")
		(23 "Eco2.User" user "User.Eco2")
		(25 "Edge.Cuts" user "Board Geometry/Outline")
		(27 "Margin" user)
		(31 "F.CrtYd" user "Package Geometry/Place Bound Top")
		(29 "B.CrtYd" user "Package Geometry/Place Bound Bottom")
		(35 "F.Fab" user "Ref Des/Assembly Top")
		(33 "B.Fab" user "Ref Des/Assembly Bottom")
	)
	(footprint ""
		(layer "F.Cu")
		(at 357.443532 12.003278 -90)
		(property "Reference" "T1P22"
			(at 0 0 270)
			(layer "F.SilkS")
			(hide yes)
			(effects
				(font
					(size 1.27 1.27)
				)
			)
		)
		(property "Value" "*"
			(at -3.302 1.12395 270)
			(unlocked yes)
			(layer "F.Fab")
			(hide yes)
			(effects
				(font
					(size 0.889 0.889)
					(thickness 0.1524)
				)
			)
		)
		(property "Device Type" "TPAD-DIFF-4P-GP_DISCRET-GB3-TPA"
			(at -3.302 -0.40005 270)
			(unlocked yes)
			(layer "F.Fab")
			(hide yes)
			(effects
				(font
					(size 0.889 0.889)
					(thickness 0.1524)
				)
			)
		)
		(duplicate_pad_numbers_are_jumpers no)
		(fp_line
			(start -2.286 2.286)
			(end 2.286 2.286)
			(stroke
				(width 0.1524)
				(type default)
			)
			(layer "F.SilkS")
		)
		(fp_line
			(start 2.286 2.286)
			(end 2.286 -2.286)
			(stroke
				(width 0.1524)
				(type default)
			)
			(layer "F.SilkS")
		)
		(fp_line
			(start -2.286 -2.286)
			(end -2.286 2.286)
			(stroke
				(width 0.1524)
				(type default)
			)
			(layer "F.SilkS")
		)
		(fp_line
			(start 2.286 -2.286)
			(end -2.286 -2.286)
			(stroke
				(width 0.1524)
				(type default)
			)
			(layer "F.SilkS")
		)
		(fp_line
			(start -2.413 -2.413)
			(end -2.413 -1.143)
			(stroke
				(width 0.4064)
				(type default)
			)
			(layer "F.SilkS")
		)
		(fp_line
			(start -1.143 -2.413)
			(end -2.413 -2.413)
			(stroke
				(width 0.4064)
				(type default)
			)
			(layer "F.SilkS")
		)
		(fp_rect
			(start -2.54 2.54)
			(end 2.54 -2.54)
			(stroke
				(width 0)
				(type default)
			)
			(fill no)
			(layer "F.CrtYd")
		)
		(fp_rect
			(start -2.54 2.54)
			(end 2.54 -2.54)
			(stroke
				(width 0)
				(type default)
			)
			(fill no)
			(layer "F.Fab")
		)
		(pad "1" thru_hole circle
			(at -1.27 -1.27 270)
			(size 1.524 1.524)
			(drill 0.9144)
			(layers "*.Cu" "*.Mask")
			(remove_unused_layers no)
			(net "L10_100OHM_6INCH_DP")
			(clearance -0.0508)
			(thermal_gap 0.127)
			(padstack
				(mode front_inner_back)
				(layer "Inner"
					(shape circle)
					(size 1.1684 1.1684)
					(clearance 0.127)
				)
				(layer "B.Cu"
					(shape circle)
					(size 1.524 1.524)
					(clearance -0.0508)
				)
			)
		)
		(pad "2" thru_hole circle
			(at 1.27 -1.27 270)
			(size 1.524 1.524)
			(drill 0.9144)
			(layers "*.Cu" "*.Mask")
			(remove_unused_layers no)
			(net "L10_100OHM_6INCH_DN")
			(clearance -0.0508)
			(thermal_gap 0.127)
			(padstack
				(mode front_inner_back)
				(layer "Inner"
					(shape circle)
					(size 1.1684 1.1684)
					(clearance 0.127)
				)
				(layer "B.Cu"
					(shape circle)
					(size 1.524 1.524)
					(clearance -0.0508)
				)
			)
		)
		(pad "GND1" thru_hole rect
			(at -1.27 1.27 270)
			(size 1.524 1.524)
			(drill 0.9144)
			(layers "*.Cu" "*.Mask")
			(remove_unused_layers no)
			(net "GND")
			(clearance -0.0508)
			(thermal_gap 0.127)
			(padstack
				(mode front_inner_back)
				(layer "Inner"
					(shape circle)
					(size 1.1684 1.1684)
					(clearance 0.127)
				)
				(layer "B.Cu"
					(shape rect)
					(size 1.524 1.524)
					(clearance -0.0508)
				)
			)
		)
		(pad "GND2" thru_hole rect
			(at 1.27 1.27 270)
			(size 1.524 1.524)
			(drill 0.9144)
			(layers "*.Cu" "*.Mask")
			(remove_unused_layers no)
			(net "GND")
			(clearance -0.0508)
			(thermal_gap 0.127)
			(padstack
				(mode front_inner_back)
				(layer "Inner"
					(shape circle)
					(size 1.1684 1.1684)
					(clearance 0.127)
				)
				(layer "B.Cu"
					(shape rect)
					(size 1.524 1.524)
					(clearance -0.0508)
				)
			)
		)
	)
	(footprint ""
		(layer "F.Cu")
		(at 173.9265 -67.945 90)
		(property "Reference" "C4D40"
			(at 0 0 90)
			(layer "F.SilkS")
			(hide yes)
			(effects
				(font
					(size 1.27 1.27)
				)
			)
		)
		(property "Value" ""
			(at 0 0 90)
			(layer "F.Fab")
			(effects
				(font
					(size 1.27 1.27)
				)
			)
		)
		(duplicate_pad_numbers_are_jumpers no)
		(fp_poly
			(pts
				(xy 0.3048 -0.1016) (xy 0.3048 0.9906) (xy -0.3048 0.9906) (xy -0.3048 -0.1016)
			)
			(stroke
				(width 0)
				(type default)
			)
			(fill no)
			(layer "F.CrtYd")
		)
		(fp_line
			(start 0.3048 -0.1016)
			(end -0.3048 -0.1016)
			(stroke
				(width 0.1)
				(type default)
			)
			(layer "F.Fab")
		)
		(fp_line
			(start -0.3048 -0.1016)
			(end -0.3048 0.9906)
			(stroke
				(width 0.1)
				(type default)
			)
			(layer "F.Fab")
		)
		(fp_line
			(start 0.3048 0.9906)
			(end 0.3048 -0.1016)
			(stroke
				(width 0.1)
				(type default)
			)
			(layer "F.Fab")
		)
		(fp_line
			(start -0.3048 0.9906)
			(end 0.3048 0.9906)
			(stroke
				(width 0.1)
				(type default)
			)
			(layer "F.Fab")
		)
		(pad "1" smd rect
			(at 0 0 90)
			(size 0.508 0.508)
			(layers "F.Cu" "F.Mask" "F.Paste")
			(net "VR_PVCCIO_CPU1_VINSEN")
		)
		(pad "2" smd rect
			(at 0 0.889 90)
			(size 0.508 0.508)
			(layers "F.Cu" "F.Mask" "F.Paste")
			(net "GND")
		)
		(zone
			(layer "F.Cu")
			(hatch none 0.5)
			(connect_pads
				(clearance 0)
			)
			(min_thickness 0.25)
			(keepout
				(tracks allowed)
				(vias not_allowed)
				(pads allowed)
				(copperpour not_allowed)
				(footprints allowed)
			)
			(placement
				(enabled no)
				(sheetname "")
			)
			(fill
				(thermal_gap 0.5)
				(thermal_bridge_width 0.5)
				(island_removal_mode 0)
			)
			(polygon
				(pts
					(xy 174.1805 -67.691) (xy 174.1805 -68.199) (xy 174.5615 -68.199) (xy 174.5615 -67.691)
				)
			)
		)
		(zone
			(layer "F.Cu")
			(hatch none 0.5)
			(connect_pads
				(clearance 0)
			)
			(min_thickness 0.25)
			(keepout
				(tracks not_allowed)
				(vias allowed)
				(pads allowed)
				(copperpour not_allowed)
				(footprints allowed)
			)
			(placement
				(enabled no)
				(sheetname "")
			)
			(fill
				(thermal_gap 0.5)
				(thermal_bridge_width 0.5)
				(island_removal_mode 0)
			)
			(polygon
				(pts
					(xy 174.5615 -67.691) (xy 174.5615 -68.199) (xy 174.1805 -68.199) (xy 174.1805 -67.691)
				)
			)
		)
	)
)
